(kicad_pcb
	(version 20241229)
	(generator "pcbnew")
	(generator_version "9.0")
	(general
		(thickness 1.62)
		(legacy_teardrops no)
	)
	(paper "A3")
	(title_block
		(title "COM Express 7 Baseboard")
		(date "2025-02-04")
		(rev "1.1.2")
		(company "Antmicro Ltd")
		(comment 1 "www.antmicro.com")
		(comment 9 "footprints 653-657 of 802")
	)
	(layers
		(0 "F.Cu" signal)
		(4 "In1.Cu" signal)
		(6 "In2.Cu" signal)
		(8 "In3.Cu" signal)
		(10 "In4.Cu" signal)
		(12 "In5.Cu" signal)
		(14 "In6.Cu" signal)
		(2 "B.Cu" signal)
		(9 "F.Adhes" user "F.Adhesive")
		(11 "B.Adhes" user "B.Adhesive")
		(13 "F.Paste" user)
		(15 "B.Paste" user)
		(5 "F.SilkS" user "F.Silkscreen")
		(7 "B.SilkS" user "B.Silkscreen")
		(1 "F.Mask" user)
		(3 "B.Mask" user)
		(17 "Dwgs.User" user "User.Drawings")
		(19 "Cmts.User" user "User.Comments")
		(21 "Eco1.User" user "User.Eco1")
		(23 "Eco2.User" user "User.Eco2")
		(25 "Edge.Cuts" user)
		(27 "Margin" user)
		(31 "F.CrtYd" user "F.Courtyard")
		(29 "B.CrtYd" user "B.Courtyard")
		(35 "F.Fab" user)
		(33 "B.Fab" user)
	)
	(footprint "antmicro-footprints:C_0603_1608Metric"
		(layer "B.Cu")
		(at 290.64 79.12 -90)
		(descr "Capacitor SMD 0603")
		(tags "capacitor 0603")
		(property "Reference" "C77"
			(at -3.31 -0.46 90)
			(layer "B.SilkS")
			(effects
				(font
					(size 0.7 0.7)
					(thickness 0.15)
				)
				(justify left bottom mirror)
			)
		)
		(property "Value" "C_22u_16V_0603"
			(at -1.42757 -1.770288 90)
			(layer "B.Fab")
			(effects
				(font
					(size 0.7 0.7)
					(thickness 0.15)
				)
				(justify left bottom mirror)
			)
		)
		(property "Datasheet" "https://product.samsungsem.com/mlcc/CL10A226MO7JZN.do"
			(at 0 0 270)
			(layer "F.Fab")
			(hide yes)
			(effects
				(font
					(size 1.27 1.27)
					(thickness 0.15)
				)
			)
		)
		(property "Author" "Antmicro"
			(at 211.52 369.76 0)
			(layer "B.Fab")
			(hide yes)
			(effects
				(font
					(size 1 1)
					(thickness 0.15)
				)
				(justify mirror)
			)
		)
		(property "Dielectric" ""
			(at 211.52 369.76 0)
			(layer "B.Fab")
			(hide yes)
			(effects
				(font
					(size 1 1)
					(thickness 0.15)
				)
				(justify mirror)
			)
		)
		(property "License" "Apache-2.0"
			(at 211.52 369.76 0)
			(layer "B.Fab")
			(hide yes)
			(effects
				(font
					(size 1 1)
					(thickness 0.15)
				)
				(justify mirror)
			)
		)
		(property "MPN" "CL10A226MO7JZNC"
			(at 211.52 369.76 0)
			(layer "B.Fab")
			(hide yes)
			(effects
				(font
					(size 1 1)
					(thickness 0.15)
				)
				(justify mirror)
			)
		)
		(property "Manufacturer" "Samsung Electro-Mechanics"
			(at 211.52 369.76 0)
			(layer "B.Fab")
			(hide yes)
			(effects
				(font
					(size 1 1)
					(thickness 0.15)
				)
				(justify mirror)
			)
		)
		(property "Public" "False"
			(at 211.52 369.76 0)
			(layer "B.Fab")
			(hide yes)
			(effects
				(font
					(size 1 1)
					(thickness 0.15)
				)
				(justify mirror)
			)
		)
		(property "Val" "22u"
			(at 211.52 369.76 0)
			(layer "B.Fab")
			(hide yes)
			(effects
				(font
					(size 1 1)
					(thickness 0.15)
				)
				(justify mirror)
			)
		)
		(property "Voltage" "16V"
			(at 211.52 369.76 0)
			(layer "B.Fab")
			(hide yes)
			(effects
				(font
					(size 1 1)
					(thickness 0.15)
				)
				(justify mirror)
			)
		)
		(sheetname "M.2 key M #2")
		(sheetfile "m2keym.kicad_sch")
		(attr smd)
		(fp_line
			(start 0.15 0.4)
			(end -0.15 0.4)
			(stroke
				(width 0.15)
				(type solid)
			)
			(layer "B.SilkS")
		)
		(fp_line
			(start 0.15 -0.4)
			(end -0.15 -0.4)
			(stroke
				(width 0.15)
				(type solid)
			)
			(layer "B.SilkS")
		)
		(fp_rect
			(start -1.25 0.65)
			(end 1.25 -0.65)
			(stroke
				(width 0.05)
				(type solid)
			)
			(fill no)
			(layer "B.CrtYd")
		)
		(fp_rect
			(start -0.8 0.4)
			(end 0.8 -0.4)
			(stroke
				(width 0.15)
				(type solid)
			)
			(fill no)
			(layer "B.Fab")
		)
		(pad "1" smd roundrect
			(at -0.7 0 270)
			(size 0.8 1)
			(layers "B.Cu" "B.Mask" "B.Paste")
			(roundrect_rratio 0.2)
			(net 1 "GND")
			(pintype "passive")
			(teardrops
				(best_length_ratio 0.2)
				(max_length 1)
				(best_width_ratio 0.9)
				(max_width 2)
				(curved_edges yes)
				(filter_ratio 0.9)
				(enabled yes)
				(allow_two_segments yes)
				(prefer_zone_connections yes)
			)
		)
		(pad "2" smd roundrect
			(at 0.7 0 270)
			(size 0.8 1)
			(layers "B.Cu" "B.Mask" "B.Paste")
			(roundrect_rratio 0.2)
			(net 970 "/M.2 key M #2/M2_3V3")
			(pintype "passive")
			(teardrops
				(best_length_ratio 0.2)
				(max_length 1)
				(best_width_ratio 0.9)
				(max_width 2)
				(curved_edges yes)
				(filter_ratio 0.9)
				(enabled yes)
				(allow_two_segments yes)
				(prefer_zone_connections yes)
			)
		)
	)
	(footprint "antmicro-footprints:C_0402_1005Metric"
		(layer "B.Cu")
		(at 198.836467 139.42053 135)
		(descr "Capacitor SMD 0402")
		(tags "capacitor SMD 0402")
		(property "Reference" "C125"
			(at -3.530586 -0.359976 135)
			(layer "B.SilkS")
			(effects
				(font
					(size 0.7 0.7)
					(thickness 0.15)
				)
				(justify right bottom mirror)
			)
		)
		(property "Value" "C_220n_0402"
			(at -1.022927 -2.155213 135)
			(layer "B.Fab")
			(effects
				(font
					(size 0.7 0.7)
					(thickness 0.15)
				)
				(justify right bottom mirror)
			)
		)
		(property "Datasheet" "https://www.yageo.com/en/Chart/Download/pdf/CC0402KRX5R6BB224"
			(at 0 0 135)
			(layer "F.Fab")
			(hide yes)
			(effects
				(font
					(size 1.27 1.27)
					(thickness 0.15)
				)
			)
		)
		(property "Author" "Antmicro"
			(at 336.3 -39.499999 45)
			(layer "B.Fab")
			(hide yes)
			(effects
				(font
					(size 1 1)
					(thickness 0.15)
				)
				(justify mirror)
			)
		)
		(property "Dielectric" ""
			(at 336.3 -39.499999 45)
			(layer "B.Fab")
			(hide yes)
			(effects
				(font
					(size 1 1)
					(thickness 0.15)
				)
				(justify mirror)
			)
		)
		(property "License" "Apache-2.0"
			(at 336.3 -39.499999 45)
			(layer "B.Fab")
			(hide yes)
			(effects
				(font
					(size 1 1)
					(thickness 0.15)
				)
				(justify mirror)
			)
		)
		(property "MPN" "CC0402KRX5R6BB224"
			(at 336.3 -39.499999 45)
			(layer "B.Fab")
			(hide yes)
			(effects
				(font
					(size 1 1)
					(thickness 0.15)
				)
				(justify mirror)
			)
		)
		(property "Manufacturer" "YAGEO"
			(at 336.3 -39.499999 45)
			(layer "B.Fab")
			(hide yes)
			(effects
				(font
					(size 1 1)
					(thickness 0.15)
				)
				(justify mirror)
			)
		)
		(property "Public" "False"
			(at 336.3 -39.499999 45)
			(layer "B.Fab")
			(hide yes)
			(effects
				(font
					(size 1 1)
					(thickness 0.15)
				)
				(justify mirror)
			)
		)
		(property "Val" "220n"
			(at 336.3 -39.499999 45)
			(layer "B.Fab")
			(hide yes)
			(effects
				(font
					(size 1 1)
					(thickness 0.15)
				)
				(justify mirror)
			)
		)
		(property "Voltage" ""
			(at 336.3 -39.499999 45)
			(layer "B.Fab")
			(hide yes)
			(effects
				(font
					(size 1 1)
					(thickness 0.15)
				)
				(justify mirror)
			)
		)
		(sheetname "PCIe redriver")
		(sheetfile "pcie_redriver.kicad_sch")
		(attr smd)
		(fp_poly
			(pts
				(xy -0.925 0.47) (xy 0.925 0.47) (xy 0.925 -0.47) (xy -0.925 -0.47)
			)
			(stroke
				(width 0.05)
				(type default)
			)
			(fill no)
			(layer "B.CrtYd")
		)
		(fp_line
			(start 0.504 -0.248)
			(end 0.504 0.25)
			(stroke
				(width 0.15)
				(type solid)
			)
			(layer "B.Fab")
		)
		(fp_line
			(start 0.504 0.25)
			(end -0.494 0.25)
			(stroke
				(width 0.15)
				(type solid)
			)
			(layer "B.Fab")
		)
		(fp_line
			(start -0.494 -0.248)
			(end 0.504 -0.248)
			(stroke
				(width 0.15)
				(type solid)
			)
			(layer "B.Fab")
		)
		(fp_line
			(start -0.494 0.25)
			(end -0.494 -0.248)
			(stroke
				(width 0.15)
				(type solid)
			)
			(layer "B.Fab")
		)
		(pad "1" smd roundrect
			(at -0.48 0 135)
			(size 0.59 0.64)
			(layers "B.Cu" "B.Mask" "B.Paste")
			(roundrect_rratio 0.25)
			(net 217 "/Com Express 7 Interfaces/PCIe_{B1x4}.RX1-")
			(pintype "passive")
			(teardrops
				(best_length_ratio 0.2)
				(max_length 1)
				(best_width_ratio 0.9)
				(max_width 2)
				(curved_edges yes)
				(filter_ratio 0.9)
				(enabled yes)
				(allow_two_segments yes)
				(prefer_zone_connections yes)
			)
		)
		(pad "2" smd roundrect
			(at 0.48 0 135)
			(size 0.59 0.64)
			(layers "B.Cu" "B.Mask" "B.Paste")
			(roundrect_rratio 0.25)
			(net 103 "/PCIe redriver/PCIe_{I}_C.RX1-")
			(pintype "passive")
			(teardrops
				(best_length_ratio 0.2)
				(max_length 1)
				(best_width_ratio 0.9)
				(max_width 2)
				(curved_edges yes)
				(filter_ratio 0.9)
				(enabled yes)
				(allow_two_segments yes)
				(prefer_zone_connections yes)
			)
		)
	)
	(footprint "antmicro-footprints:R_0402_1005Metric"
		(layer "B.Cu")
		(at 309.824999 121.96 -90)
		(descr "Resistor SMD 0402")
		(tags "resistor SMD 0402")
		(property "Reference" "R88"
			(at 0.8 -0.475001 90)
			(layer "B.SilkS")
			(effects
				(font
					(size 0.7 0.7)
					(thickness 0.15)
				)
				(justify left bottom mirror)
			)
		)
		(property "Value" "R_68k_0402"
			(at -1.011843 -1.772047 90)
			(layer "B.Fab")
			(effects
				(font
					(size 0.7 0.7)
					(thickness 0.15)
				)
				(justify left bottom mirror)
			)
		)
		(property "Datasheet" "https://www.bourns.com/docs/product-datasheets/cr.pdf"
			(at 0 0 270)
			(layer "F.Fab")
			(hide yes)
			(effects
				(font
					(size 1.27 1.27)
					(thickness 0.15)
				)
			)
		)
		(property "Author" "Antmicro"
			(at 187.864999 431.784999 0)
			(layer "B.Fab")
			(hide yes)
			(effects
				(font
					(size 1 1)
					(thickness 0.15)
				)
				(justify mirror)
			)
		)
		(property "License" "Apache-2.0"
			(at 187.864999 431.784999 0)
			(layer "B.Fab")
			(hide yes)
			(effects
				(font
					(size 1 1)
					(thickness 0.15)
				)
				(justify mirror)
			)
		)
		(property "MPN" "CR0402-FX-6802GLF"
			(at 187.864999 431.784999 0)
			(layer "B.Fab")
			(hide yes)
			(effects
				(font
					(size 1 1)
					(thickness 0.15)
				)
				(justify mirror)
			)
		)
		(property "Manufacturer" "Bourns"
			(at 187.864999 431.784999 0)
			(layer "B.Fab")
			(hide yes)
			(effects
				(font
					(size 1 1)
					(thickness 0.15)
				)
				(justify mirror)
			)
		)
		(property "Public" "False"
			(at 187.864999 431.784999 0)
			(layer "B.Fab")
			(hide yes)
			(effects
				(font
					(size 1 1)
					(thickness 0.15)
				)
				(justify mirror)
			)
		)
		(property "Tolerance" "1%"
			(at 187.864999 431.784999 0)
			(layer "B.Fab")
			(hide yes)
			(effects
				(font
					(size 1 1)
					(thickness 0.15)
				)
				(justify mirror)
			)
		)
		(property "Val" "68k"
			(at 187.864999 431.784999 0)
			(layer "B.Fab")
			(hide yes)
			(effects
				(font
					(size 1 1)
					(thickness 0.15)
				)
				(justify mirror)
			)
		)
		(sheetname "Power")
		(sheetfile "power.kicad_sch")
		(attr smd dnp)
		(fp_rect
			(start -0.925 0.47)
			(end 0.925 -0.47)
			(stroke
				(width 0.05)
				(type default)
			)
			(fill no)
			(layer "B.CrtYd")
		)
		(fp_rect
			(start -0.5 0.25)
			(end 0.5 -0.25)
			(stroke
				(width 0.15)
				(type solid)
			)
			(fill no)
			(layer "B.Fab")
		)
		(pad "1" smd roundrect
			(at -0.48 0 270)
			(size 0.59 0.64)
			(layers "B.Cu" "B.Mask" "B.Paste")
			(roundrect_rratio 0.25)
			(net 575 "Net-(U18-MODE)")
			(pintype "passive")
			(teardrops
				(best_length_ratio 0.2)
				(max_length 1)
				(best_width_ratio 0.9)
				(max_width 2)
				(curved_edges yes)
				(filter_ratio 0.9)
				(enabled yes)
				(allow_two_segments yes)
				(prefer_zone_connections yes)
			)
		)
		(pad "2" smd roundrect
			(at 0.48 0 270)
			(size 0.59 0.64)
			(layers "B.Cu" "B.Mask" "B.Paste")
			(roundrect_rratio 0.25)
			(net 63 "Net-(U18-V_{CC})")
			(pintype "passive")
			(teardrops
				(best_length_ratio 0.2)
				(max_length 1)
				(best_width_ratio 0.9)
				(max_width 2)
				(curved_edges yes)
				(filter_ratio 0.9)
				(enabled yes)
				(allow_two_segments yes)
				(prefer_zone_connections yes)
			)
		)
	)
	(footprint "antmicro-footprints:TP_SMD_0.75mm"
		(layer "B.Cu")
		(at 145.35 167.21 180)
		(property "Reference" "TP5"
			(at -2.45 -0.4 0)
			(layer "B.SilkS")
			(effects
				(font
					(size 0.7 0.7)
					(thickness 0.15)
				)
				(justify left bottom mirror)
			)
		)
		(property "Value" "TP_0.75mm_SMD"
			(at 0 -1.2 0)
			(layer "B.Fab")
			(effects
				(font
					(size 0.7 0.7)
					(thickness 0.15)
				)
				(justify left bottom mirror)
			)
		)
		(property "Author" "Antmicro"
			(at 290.7 334.42 0)
			(layer "B.Fab")
			(hide yes)
			(effects
				(font
					(size 1 1)
					(thickness 0.15)
				)
				(justify mirror)
			)
		)
		(property "License" "Apache-2.0"
			(at 290.7 334.42 0)
			(layer "B.Fab")
			(hide yes)
			(effects
				(font
					(size 1 1)
					(thickness 0.15)
				)
				(justify mirror)
			)
		)
		(property "MPN" ""
			(at 290.7 334.42 0)
			(layer "B.Fab")
			(hide yes)
			(effects
				(font
					(size 1 1)
					(thickness 0.15)
				)
				(justify mirror)
			)
		)
		(property "Manufacturer" ""
			(at 290.7 334.42 0)
			(layer "B.Fab")
			(hide yes)
			(effects
				(font
					(size 1 1)
					(thickness 0.15)
				)
				(justify mirror)
			)
		)
		(property "Public" "False"
			(at 290.7 334.42 0)
			(layer "B.Fab")
			(hide yes)
			(effects
				(font
					(size 1 1)
					(thickness 0.15)
				)
				(justify mirror)
			)
		)
		(sheetname "2xSFP+")
		(sheetfile "2xSFP+.kicad_sch")
		(attr exclude_from_pos_files exclude_from_bom)
		(fp_circle
			(center 0 0)
			(end 0.475 0)
			(stroke
				(width 0.05)
				(type default)
			)
			(fill no)
			(layer "B.CrtYd")
		)
		(pad "1" smd circle
			(at 0 0 180)
			(size 0.75 0.75)
			(layers "B.Cu" "B.Mask")
			(net 168 "Net-(J2A-RX_{LOS})")
			(pinfunction "1")
			(pintype "passive")
			(teardrops
				(best_length_ratio 0.4)
				(max_length 1)
				(best_width_ratio 0.9)
				(max_width 2)
				(curved_edges yes)
				(filter_ratio 0.9)
				(enabled yes)
				(allow_two_segments yes)
				(prefer_zone_connections yes)
			)
		)
	)
	(footprint "antmicro-footprints:C_0402_1005Metric"
		(layer "B.Cu")
		(at 151.45 132.36 -90)
		(descr "Capacitor SMD 0402")
		(tags "capacitor SMD 0402")
		(property "Reference" "C165"
			(at -3.65 -0.45 90)
			(layer "B.SilkS")
			(effects
				(font
					(size 0.7 0.7)
					(thickness 0.15)
				)
				(justify left bottom mirror)
			)
		)
		(property "Value" "C_100n_0402"
			(at -1.022927 -2.155213 90)
			(layer "B.Fab")
			(effects
				(font
					(size 0.7 0.7)
					(thickness 0.15)
				)
				(justify left bottom mirror)
			)
		)
		(property "Datasheet" "https://www.murata.com/products/productdetail?partno=GRM155R61H104KE14%23"
			(at 0 0 270)
			(layer "F.Fab")
			(hide yes)
			(effects
				(font
					(size 1.27 1.27)
					(thickness 0.15)
				)
			)
		)
		(property "Author" "Antmicro"
			(at 19.09 283.81 0)
			(layer "B.Fab")
			(hide yes)
			(effects
				(font
					(size 1 1)
					(thickness 0.15)
				)
				(justify mirror)
			)
		)
		(property "Dielectric" "X5R"
			(at 19.09 283.81 0)
			(layer "B.Fab")
			(hide yes)
			(effects
				(font
					(size 1 1)
					(thickness 0.15)
				)
				(justify mirror)
			)
		)
		(property "License" "Apache-2.0"
			(at 19.09 283.81 0)
			(layer "B.Fab")
			(hide yes)
			(effects
				(font
					(size 1 1)
					(thickness 0.15)
				)
				(justify mirror)
			)
		)
		(property "MPN" "GRM155R61H104KE14D"
			(at 19.09 283.81 0)
			(layer "B.Fab")
			(hide yes)
			(effects
				(font
					(size 1 1)
					(thickness 0.15)
				)
				(justify mirror)
			)
		)
		(property "Manufacturer" "Murata"
			(at 19.09 283.81 0)
			(layer "B.Fab")
			(hide yes)
			(effects
				(font
					(size 1 1)
					(thickness 0.15)
				)
				(justify mirror)
			)
		)
		(property "Public" "False"
			(at 19.09 283.81 0)
			(layer "B.Fab")
			(hide yes)
			(effects
				(font
					(size 1 1)
					(thickness 0.15)
				)
				(justify mirror)
			)
		)
		(property "Val" "100n"
			(at 19.09 283.81 0)
			(layer "B.Fab")
			(hide yes)
			(effects
				(font
					(size 1 1)
					(thickness 0.15)
				)
				(justify mirror)
			)
		)
		(property "Voltage" "50V"
			(at 19.09 283.81 0)
			(layer "B.Fab")
			(hide yes)
			(effects
				(font
					(size 1 1)
					(thickness 0.15)
				)
				(justify mirror)
			)
		)
		(sheetname "KR to SFI #1")
		(sheetfile "kr_sfi.kicad_sch")
		(attr smd)
		(fp_rect
			(start -0.925 0.47)
			(end 0.925 -0.47)
			(stroke
				(width 0.05)
				(type default)
			)
			(fill no)
			(layer "B.CrtYd")
		)
		(fp_line
			(start -0.494 0.25)
			(end -0.494 -0.248)
			(stroke
				(width 0.15)
				(type solid)
			)
			(layer "B.Fab")
		)
		(fp_line
			(start 0.504 0.25)
			(end -0.494 0.25)
			(stroke
				(width 0.15)
				(type solid)
			)
			(layer "B.Fab")
		)
		(fp_line
			(start -0.494 -0.248)
			(end 0.504 -0.248)
			(stroke
				(width 0.15)
				(type solid)
			)
			(layer "B.Fab")
		)
		(fp_line
			(start 0.504 -0.248)
			(end 0.504 0.25)
			(stroke
				(width 0.15)
				(type solid)
			)
			(layer "B.Fab")
		)
		(pad "1" smd roundrect
			(at -0.48 0 270)
			(size 0.59 0.64)
			(layers "B.Cu" "B.Mask" "B.Paste")
			(roundrect_rratio 0.25)
			(net 1 "GND")
			(pintype "passive")
			(teardrops
				(best_length_ratio 0.2)
				(max_length 1)
				(best_width_ratio 0.9)
				(max_width 2)
				(curved_edges yes)
				(filter_ratio 0.9)
				(enabled yes)
				(allow_two_segments yes)
				(prefer_zone_connections yes)
			)
		)
		(pad "2" smd roundrect
			(at 0.48 0 270)
			(size 0.59 0.64)
			(layers "B.Cu" "B.Mask" "B.Paste")
			(roundrect_rratio 0.25)
			(net 74 "+1V0")
			(pintype "passive")
			(teardrops
				(best_length_ratio 0.2)
				(max_length 1)
				(best_width_ratio 0.9)
				(max_width 2)
				(curved_edges yes)
				(filter_ratio 0.9)
				(enabled yes)
				(allow_two_segments yes)
				(prefer_zone_connections yes)
			)
		)
	)
)
